(kicad_pcb
	(version 20260206)
	(generator "pcbnew")
	(generator_version "10.0")
	(general
		(thickness 1.6)
		(legacy_teardrops no)
	)
	(paper "A4")
	(title_block
		(title "01162023_DA0F0TEBIF0_F0T_Expander_BD_F_brd_V02_OCP.brd")
		(comment 1 "Grand Teton / footprints 4169-4173 of 9728")
	)
	(layers
		(0 "F.Cu" signal "TOP")
		(4 "In1.Cu" signal "GND")
		(6 "In2.Cu" signal "VCC")
		(8 "In3.Cu" signal "VCC1")
		(10 "In4.Cu" signal "GND1")
		(12 "In5.Cu" signal "IN1")
		(14 "In6.Cu" signal "GND2")
		(16 "In7.Cu" signal "IN2")
		(18 "In8.Cu" signal "GND3")
		(20 "In9.Cu" signal "IN3")
		(22 "In10.Cu" signal "GND4")
		(24 "In11.Cu" signal "IN4")
		(26 "In12.Cu" signal "GND5")
		(28 "In13.Cu" signal "IN5")
		(30 "In14.Cu" signal "GND6")
		(32 "In15.Cu" signal "IN6")
		(34 "In16.Cu" signal "GND7")
		(2 "B.Cu" signal "BOTTOM")
		(9 "F.Adhes" user "F.Adhesive")
		(11 "B.Adhes" user "B.Adhesive")
		(13 "F.Paste" user "Package Geometry/Pastemask Top")
		(15 "B.Paste" user "Package Geometry/Pastemask Bottom")
		(5 "F.SilkS" user "Ref Des/Silkscreen Top")
		(7 "B.SilkS" user "Ref Des/Silkscreen Bottom")
		(1 "F.Mask" user "Board Geometry/Soldermask Top")
		(3 "B.Mask" user "Board Geometry/Soldermask Bottom")
		(17 "Dwgs.User" user "User.Drawings")
		(19 "Cmts.User" user "User.Comments")
		(21 "Eco1.User" user "User.Eco1")
		(23 "Eco2.User" user "User.Eco2")
		(25 "Edge.Cuts" user "Board Geometry/Outline")
		(27 "Margin" user)
		(31 "F.CrtYd" user "Package Geometry/Place Bound Top")
		(29 "B.CrtYd" user "Package Geometry/Place Bound Bottom")
		(35 "F.Fab" user "Ref Des/Assembly Top")
		(33 "B.Fab" user "Ref Des/Assembly Bottom")
	)
	(footprint ""
		(layer "F.Cu")
		(at 451.362318 -22.955504 -90)
		(property "Reference" "C2735"
			(at 0 0 270)
			(layer "F.SilkS")
			(hide yes)
			(effects
				(font
					(size 1.27 1.27)
				)
			)
		)
		(property "Value" ""
			(at 0 0 270)
			(layer "F.Fab")
			(effects
				(font
					(size 1.27 1.27)
				)
			)
		)
		(duplicate_pad_numbers_are_jumpers no)
		(fp_line
			(start -0.7874 0.4064)
			(end -0.7874 -0.4064)
			(stroke
				(width 0.1524)
				(type default)
			)
			(layer "F.SilkS")
		)
		(fp_line
			(start 0.7874 0.4064)
			(end -0.7874 0.4064)
			(stroke
				(width 0.1524)
				(type default)
			)
			(layer "F.SilkS")
		)
		(fp_line
			(start -0.7874 -0.4064)
			(end 0.7874 -0.4064)
			(stroke
				(width 0.1524)
				(type default)
			)
			(layer "F.SilkS")
		)
		(fp_line
			(start 0.7874 -0.4064)
			(end 0.7874 0.4064)
			(stroke
				(width 0.1524)
				(type default)
			)
			(layer "F.SilkS")
		)
		(fp_line
			(start -0.67945 0.3048)
			(end -0.67945 -0.305054)
			(stroke
				(width 0.1)
				(type default)
			)
			(layer "F.Fab")
		)
		(fp_line
			(start -0.12065 0.3048)
			(end -0.67945 0.3048)
			(stroke
				(width 0.1)
				(type default)
			)
			(layer "F.Fab")
		)
		(fp_line
			(start 0.120396 0.3048)
			(end 0.120396 0.2794)
			(stroke
				(width 0.1)
				(type default)
			)
			(layer "F.Fab")
		)
		(fp_line
			(start 0.67945 0.3048)
			(end 0.120396 0.3048)
			(stroke
				(width 0.1)
				(type default)
			)
			(layer "F.Fab")
		)
		(fp_line
			(start -0.12065 0.2794)
			(end -0.12065 0.3048)
			(stroke
				(width 0.1)
				(type default)
			)
			(layer "F.Fab")
		)
		(fp_line
			(start 0.120396 0.2794)
			(end -0.12065 0.2794)
			(stroke
				(width 0.1)
				(type default)
			)
			(layer "F.Fab")
		)
		(fp_line
			(start -0.12065 -0.2794)
			(end 0.12065 -0.2794)
			(stroke
				(width 0.1)
				(type default)
			)
			(layer "F.Fab")
		)
		(fp_line
			(start 0.12065 -0.2794)
			(end 0.12065 -0.3048)
			(stroke
				(width 0.1)
				(type default)
			)
			(layer "F.Fab")
		)
		(fp_line
			(start 0.12065 -0.3048)
			(end 0.67945 -0.3048)
			(stroke
				(width 0.1)
				(type default)
			)
			(layer "F.Fab")
		)
		(fp_line
			(start 0.67945 -0.3048)
			(end 0.67945 0.3048)
			(stroke
				(width 0.1)
				(type default)
			)
			(layer "F.Fab")
		)
		(fp_line
			(start -0.67945 -0.305054)
			(end -0.12065 -0.305054)
			(stroke
				(width 0.1)
				(type default)
			)
			(layer "F.Fab")
		)
		(fp_line
			(start -0.12065 -0.305054)
			(end -0.12065 -0.2794)
			(stroke
				(width 0.1)
				(type default)
			)
			(layer "F.Fab")
		)
		(pad "1" smd circle
			(at -0.40005 0 270)
			(size 0 0)
			(layers "F.Cu" "F.Mask" "F.Paste")
			(net "GND")
		)
		(pad "2" smd circle
			(at 0.40005 0 270)
			(size 0 0)
			(layers "F.Cu" "F.Mask" "F.Paste")
			(net "P3V3_AUX")
		)
	)
	(footprint ""
		(layer "F.Cu")
		(at 376.936 -186.817)
		(property "Reference" "R4603"
			(at 0 0 0)
			(layer "F.SilkS")
			(hide yes)
			(effects
				(font
					(size 1.27 1.27)
				)
			)
		)
		(property "Value" ""
			(at 0 0 0)
			(layer "F.Fab")
			(effects
				(font
					(size 1.27 1.27)
				)
			)
		)
		(duplicate_pad_numbers_are_jumpers no)
		(fp_line
			(start -0.7874 -0.4064)
			(end 0.7874 -0.4064)
			(stroke
				(width 0.1524)
				(type default)
			)
			(layer "F.SilkS")
		)
		(fp_line
			(start -0.7874 0.4064)
			(end -0.7874 -0.4064)
			(stroke
				(width 0.1524)
				(type default)
			)
			(layer "F.SilkS")
		)
		(fp_line
			(start 0.7874 -0.4064)
			(end 0.7874 0.4064)
			(stroke
				(width 0.1524)
				(type default)
			)
			(layer "F.SilkS")
		)
		(fp_line
			(start 0.7874 0.4064)
			(end -0.7874 0.4064)
			(stroke
				(width 0.1524)
				(type default)
			)
			(layer "F.SilkS")
		)
		(fp_line
			(start -0.67945 -0.305054)
			(end -0.12065 -0.305054)
			(stroke
				(width 0.1)
				(type default)
			)
			(layer "F.Fab")
		)
		(fp_line
			(start -0.67945 0.3048)
			(end -0.67945 -0.305054)
			(stroke
				(width 0.1)
				(type default)
			)
			(layer "F.Fab")
		)
		(fp_line
			(start -0.12065 -0.305054)
			(end -0.12065 -0.2794)
			(stroke
				(width 0.1)
				(type default)
			)
			(layer "F.Fab")
		)
		(fp_line
			(start -0.12065 -0.2794)
			(end 0.12065 -0.2794)
			(stroke
				(width 0.1)
				(type default)
			)
			(layer "F.Fab")
		)
		(fp_line
			(start -0.12065 0.2794)
			(end -0.12065 0.3048)
			(stroke
				(width 0.1)
				(type default)
			)
			(layer "F.Fab")
		)
		(fp_line
			(start -0.12065 0.3048)
			(end -0.67945 0.3048)
			(stroke
				(width 0.1)
				(type default)
			)
			(layer "F.Fab")
		)
		(fp_line
			(start 0.120396 0.2794)
			(end -0.12065 0.2794)
			(stroke
				(width 0.1)
				(type default)
			)
			(layer "F.Fab")
		)
		(fp_line
			(start 0.120396 0.3048)
			(end 0.120396 0.2794)
			(stroke
				(width 0.1)
				(type default)
			)
			(layer "F.Fab")
		)
		(fp_line
			(start 0.12065 -0.3048)
			(end 0.67945 -0.3048)
			(stroke
				(width 0.1)
				(type default)
			)
			(layer "F.Fab")
		)
		(fp_line
			(start 0.12065 -0.2794)
			(end 0.12065 -0.3048)
			(stroke
				(width 0.1)
				(type default)
			)
			(layer "F.Fab")
		)
		(fp_line
			(start 0.67945 -0.3048)
			(end 0.67945 0.3048)
			(stroke
				(width 0.1)
				(type default)
			)
			(layer "F.Fab")
		)
		(fp_line
			(start 0.67945 0.3048)
			(end 0.120396 0.3048)
			(stroke
				(width 0.1)
				(type default)
			)
			(layer "F.Fab")
		)
		(pad "1" smd circle
			(at -0.40005 0)
			(size 0 0)
			(layers "F.Cu" "F.Mask" "F.Paste")
			(net "P3V3_AUX")
		)
		(pad "2" smd circle
			(at 0.40005 0)
			(size 0 0)
			(layers "F.Cu" "F.Mask" "F.Paste")
			(net "NIC1_PEX_PWR_EN_R")
		)
	)
	(footprint ""
		(layer "F.Cu")
		(at 232.936542 -451.107556 180)
		(property "Reference" "X68"
			(at -0.1778 -1.92913 180)
			(unlocked yes)
			(layer "F.SilkS")
			(effects
				(font
					(size 0.7874 0.5842)
					(thickness 0.1524)
				)
				(justify left)
			)
		)
		(property "Value" ""
			(at 0 0 180)
			(layer "F.Fab")
			(effects
				(font
					(size 1.27 1.27)
				)
			)
		)
		(property "Device Type" "TP_TDR_4P_FTS_MPKT4_H025P0200_IO_TP15_TP_TDR_4P_DIP"
			(at 1.30175 1.27 270)
			(unlocked yes)
			(layer "F.Fab")
			(hide yes)
			(effects
				(font
					(size 0.635 0.4064)
					(thickness 0.1524)
				)
			)
		)
		(property "User Part Number" "TP15"
			(at 1.30175 1.27 270)
			(unlocked yes)
			(layer "Cmts.User")
			(hide yes)
			(effects
				(font
					(size 0.635 0.4064)
					(thickness 0.1524)
				)
			)
		)
		(duplicate_pad_numbers_are_jumpers no)
		(fp_line
			(start 2.54 3.81)
			(end 2.54 3.6703)
			(stroke
				(width 0.1524)
				(type default)
			)
			(layer "F.SilkS")
		)
		(fp_line
			(start 2.54 1.4097)
			(end 2.54 1.1303)
			(stroke
				(width 0.1524)
				(type default)
			)
			(layer "F.SilkS")
		)
		(fp_line
			(start 2.54 -1.1303)
			(end 2.54 -1.27)
			(stroke
				(width 0.1524)
				(type default)
			)
			(layer "F.SilkS")
		)
		(fp_line
			(start 2.54 -1.27)
			(end 0 -1.27)
			(stroke
				(width 0.1524)
				(type default)
			)
			(layer "F.SilkS")
		)
		(fp_line
			(start 0 3.81)
			(end 2.54 3.81)
			(stroke
				(width 0.1524)
				(type default)
			)
			(layer "F.SilkS")
		)
		(fp_line
			(start 0 3.175)
			(end 0 3.81)
			(stroke
				(width 0.1524)
				(type default)
			)
			(layer "F.SilkS")
		)
		(fp_line
			(start 0 0.635)
			(end 0 1.905)
			(stroke
				(width 0.1524)
				(type default)
			)
			(layer "F.SilkS")
		)
		(fp_line
			(start 0 -1.27)
			(end 0 -0.635)
			(stroke
				(width 0.1524)
				(type default)
			)
			(layer "F.SilkS")
		)
		(fp_poly
			(pts
				(xy -0.761746 0) (xy -2.285746 -0.762) (xy -2.285746 0.762)
			)
			(stroke
				(width 0)
				(type default)
			)
			(fill yes)
			(layer "F.SilkS")
		)
		(fp_line
			(start 2.54 3.81)
			(end 2.54 -1.27)
			(stroke
				(width 0.1)
				(type default)
			)
			(layer "F.Fab")
		)
		(fp_line
			(start 2.54 -1.27)
			(end 0 -1.27)
			(stroke
				(width 0.1)
				(type default)
			)
			(layer "F.Fab")
		)
		(fp_line
			(start 0 3.81)
			(end 2.54 3.81)
			(stroke
				(width 0.1)
				(type default)
			)
			(layer "F.Fab")
		)
		(fp_line
			(start 0 -1.27)
			(end 0 3.81)
			(stroke
				(width 0.1)
				(type default)
			)
			(layer "F.Fab")
		)
		(fp_poly
			(pts
				(xy -0.761746 0) (xy -2.285746 -0.762) (xy -2.285746 0.762)
			)
			(stroke
				(width 0)
				(type default)
			)
			(fill yes)
			(layer "F.Fab")
		)
		(pad "1" thru_hole circle
			(at 0 0 180)
			(size 1.0033 1.0033)
			(drill 0.249936)
			(layers "*.Cu" "*.Mask")
			(remove_unused_layers no)
			(net "TDR_DIFF_100_IN1_DIP")
			(clearance 0.10795)
			(thermal_gap 0.10795)
			(padstack
				(mode front_inner_back)
				(layer "Inner"
					(shape circle)
					(size 0.8001 0.8001)
					(clearance 0.1524)
				)
				(layer "B.Cu"
					(shape circle)
					(size 1.0033 1.0033)
					(clearance 0.10795)
				)
			)
		)
		(pad "2" thru_hole circle
			(at 2.54 0 180)
			(size 1.9939 1.9939)
			(drill 0.249936)
			(layers "*.Cu" "*.Mask")
			(remove_unused_layers no)
			(net "COUPON_GND1")
			(clearance 0.10795)
			(thermal_gap 0.10795)
			(padstack
				(mode front_inner_back)
				(layer "Inner"
					(shape circle)
					(size 0.8001 0.8001)
					(clearance 0.1524)
				)
				(layer "B.Cu"
					(shape circle)
					(size 1.9939 1.9939)
					(clearance 0.10795)
				)
			)
		)
		(pad "3" thru_hole circle
			(at 2.54 2.54 180)
			(size 1.9939 1.9939)
			(drill 0.249936)
			(layers "*.Cu" "*.Mask")
			(remove_unused_layers no)
			(net "COUPON_GND1")
			(clearance 0.10795)
			(thermal_gap 0.10795)
			(padstack
				(mode front_inner_back)
				(layer "Inner"
					(shape circle)
					(size 0.8001 0.8001)
					(clearance 0.1524)
				)
				(layer "B.Cu"
					(shape circle)
					(size 1.9939 1.9939)
					(clearance 0.10795)
				)
			)
		)
		(pad "4" thru_hole circle
			(at 0 2.54 180)
			(size 1.0033 1.0033)
			(drill 0.249936)
			(layers "*.Cu" "*.Mask")
			(remove_unused_layers no)
			(net "TDR_DIFF_100_IN1_DIN")
			(clearance 0.10795)
			(thermal_gap 0.10795)
			(padstack
				(mode front_inner_back)
				(layer "Inner"
					(shape circle)
					(size 0.8001 0.8001)
					(clearance 0.1524)
				)
				(layer "B.Cu"
					(shape circle)
					(size 1.0033 1.0033)
					(clearance 0.10795)
				)
			)
		)
	)
	(footprint ""
		(layer "F.Cu")
		(at 80.53959 -158.219648)
		(property "Reference" "R59"
			(at 0 0 0)
			(layer "F.SilkS")
			(hide yes)
			(effects
				(font
					(size 1.27 1.27)
				)
			)
		)
		(property "Value" ""
			(at 0 0 0)
			(layer "F.Fab")
			(effects
				(font
					(size 1.27 1.27)
				)
			)
		)
		(duplicate_pad_numbers_are_jumpers no)
		(fp_line
			(start -0.7874 -0.4064)
			(end 0.7874 -0.4064)
			(stroke
				(width 0.1524)
				(type default)
			)
			(layer "F.SilkS")
		)
		(fp_line
			(start -0.7874 0.4064)
			(end -0.7874 -0.4064)
			(stroke
				(width 0.1524)
				(type default)
			)
			(layer "F.SilkS")
		)
		(fp_line
			(start 0.7874 -0.4064)
			(end 0.7874 0.4064)
			(stroke
				(width 0.1524)
				(type default)
			)
			(layer "F.SilkS")
		)
		(fp_line
			(start 0.7874 0.4064)
			(end -0.7874 0.4064)
			(stroke
				(width 0.1524)
				(type default)
			)
			(layer "F.SilkS")
		)
		(fp_line
			(start -0.67945 -0.305054)
			(end -0.12065 -0.305054)
			(stroke
				(width 0.1)
				(type default)
			)
			(layer "F.Fab")
		)
		(fp_line
			(start -0.67945 0.3048)
			(end -0.67945 -0.305054)
			(stroke
				(width 0.1)
				(type default)
			)
			(layer "F.Fab")
		)
		(fp_line
			(start -0.12065 -0.305054)
			(end -0.12065 -0.2794)
			(stroke
				(width 0.1)
				(type default)
			)
			(layer "F.Fab")
		)
		(fp_line
			(start -0.12065 -0.2794)
			(end 0.12065 -0.2794)
			(stroke
				(width 0.1)
				(type default)
			)
			(layer "F.Fab")
		)
		(fp_line
			(start -0.12065 0.2794)
			(end -0.12065 0.3048)
			(stroke
				(width 0.1)
				(type default)
			)
			(layer "F.Fab")
		)
		(fp_line
			(start -0.12065 0.3048)
			(end -0.67945 0.3048)
			(stroke
				(width 0.1)
				(type default)
			)
			(layer "F.Fab")
		)
		(fp_line
			(start 0.120396 0.2794)
			(end -0.12065 0.2794)
			(stroke
				(width 0.1)
				(type default)
			)
			(layer "F.Fab")
		)
		(fp_line
			(start 0.120396 0.3048)
			(end 0.120396 0.2794)
			(stroke
				(width 0.1)
				(type default)
			)
			(layer "F.Fab")
		)
		(fp_line
			(start 0.12065 -0.3048)
			(end 0.67945 -0.3048)
			(stroke
				(width 0.1)
				(type default)
			)
			(layer "F.Fab")
		)
		(fp_line
			(start 0.12065 -0.2794)
			(end 0.12065 -0.3048)
			(stroke
				(width 0.1)
				(type default)
			)
			(layer "F.Fab")
		)
		(fp_line
			(start 0.67945 -0.3048)
			(end 0.67945 0.3048)
			(stroke
				(width 0.1)
				(type default)
			)
			(layer "F.Fab")
		)
		(fp_line
			(start 0.67945 0.3048)
			(end 0.120396 0.3048)
			(stroke
				(width 0.1)
				(type default)
			)
			(layer "F.Fab")
		)
		(pad "1" smd circle
			(at -0.40005 0)
			(size 0 0)
			(layers "F.Cu" "F.Mask" "F.Paste")
			(net "PRSNTB3_NIC1_N")
		)
		(pad "2" smd circle
			(at 0.40005 0)
			(size 0 0)
			(layers "F.Cu" "F.Mask" "F.Paste")
			(net "P3V3_AUX")
		)
	)
	(footprint ""
		(layer "F.Cu")
		(at 242.91671 -162.003994 90)
		(property "Reference" "PC811"
			(at 0 0 90)
			(layer "F.SilkS")
			(hide yes)
			(effects
				(font
					(size 1.27 1.27)
				)
			)
		)
		(property "Value" ""
			(at 0 0 90)
			(layer "F.Fab")
			(effects
				(font
					(size 1.27 1.27)
				)
			)
		)
		(duplicate_pad_numbers_are_jumpers no)
		(fp_line
			(start 0.7874 -0.4064)
			(end 0.7874 0.4064)
			(stroke
				(width 0.1524)
				(type default)
			)
			(layer "F.SilkS")
		)
		(fp_line
			(start -0.7874 -0.4064)
			(end 0.7874 -0.4064)
			(stroke
				(width 0.1524)
				(type default)
			)
			(layer "F.SilkS")
		)
		(fp_line
			(start 0.7874 0.4064)
			(end -0.7874 0.4064)
			(stroke
				(width 0.1524)
				(type default)
			)
			(layer "F.SilkS")
		)
		(fp_line
			(start -0.7874 0.4064)
			(end -0.7874 -0.4064)
			(stroke
				(width 0.1524)
				(type default)
			)
			(layer "F.SilkS")
		)
		(fp_line
			(start -0.12065 -0.305054)
			(end -0.12065 -0.2794)
			(stroke
				(width 0.1)
				(type default)
			)
			(layer "F.Fab")
		)
		(fp_line
			(start -0.67945 -0.305054)
			(end -0.12065 -0.305054)
			(stroke
				(width 0.1)
				(type default)
			)
			(layer "F.Fab")
		)
		(fp_line
			(start 0.67945 -0.3048)
			(end 0.67945 0.3048)
			(stroke
				(width 0.1)
				(type default)
			)
			(layer "F.Fab")
		)
		(fp_line
			(start 0.12065 -0.3048)
			(end 0.67945 -0.3048)
			(stroke
				(width 0.1)
				(type default)
			)
			(layer "F.Fab")
		)
		(fp_line
			(start 0.12065 -0.2794)
			(end 0.12065 -0.3048)
			(stroke
				(width 0.1)
				(type default)
			)
			(layer "F.Fab")
		)
		(fp_line
			(start -0.12065 -0.2794)
			(end 0.12065 -0.2794)
			(stroke
				(width 0.1)
				(type default)
			)
			(layer "F.Fab")
		)
		(fp_line
			(start 0.120396 0.2794)
			(end -0.12065 0.2794)
			(stroke
				(width 0.1)
				(type default)
			)
			(layer "F.Fab")
		)
		(fp_line
			(start -0.12065 0.2794)
			(end -0.12065 0.3048)
			(stroke
				(width 0.1)
				(type default)
			)
			(layer "F.Fab")
		)
		(fp_line
			(start 0.67945 0.3048)
			(end 0.120396 0.3048)
			(stroke
				(width 0.1)
				(type default)
			)
			(layer "F.Fab")
		)
		(fp_line
			(start 0.120396 0.3048)
			(end 0.120396 0.2794)
			(stroke
				(width 0.1)
				(type default)
			)
			(layer "F.Fab")
		)
		(fp_line
			(start -0.12065 0.3048)
			(end -0.67945 0.3048)
			(stroke
				(width 0.1)
				(type default)
			)
			(layer "F.Fab")
		)
		(fp_line
			(start -0.67945 0.3048)
			(end -0.67945 -0.305054)
			(stroke
				(width 0.1)
				(type default)
			)
			(layer "F.Fab")
		)
		(pad "1" smd circle
			(at -0.40005 0 90)
			(size 0 0)
			(layers "F.Cu" "F.Mask" "F.Paste")
			(net "P12V_NIC4_CO_SS")
		)
		(pad "2" smd circle
			(at 0.40005 0 90)
			(size 0 0)
			(layers "F.Cu" "F.Mask" "F.Paste")
			(net "GND")
		)
	)
)
